(kicad_pcb
	(version 20240108)
	(generator "pcbnew")
	(generator_version "8.0")
	(general
		(thickness 1.62)
		(legacy_teardrops no)
	)
	(paper "A4")
	(title_block
		(title "Jetson Orin Baseboard")
		(date "2025-03-12")
		(rev "1.3.4")
		(company "Antmicro Ltd")
		(comment 1 "www.antmicro.com")
		(comment 9 "footprints 162-164 of 677")
	)
	(layers
		(0 "F.Cu" signal)
		(1 "In1.Cu" signal)
		(2 "In2.Cu" signal)
		(3 "In3.Cu" signal)
		(4 "In4.Cu" jumper)
		(5 "In5.Cu" signal)
		(6 "In6.Cu" signal)
		(31 "B.Cu" signal)
		(32 "B.Adhes" user "B.Adhesive")
		(33 "F.Adhes" user "F.Adhesive")
		(34 "B.Paste" user)
		(35 "F.Paste" user)
		(36 "B.SilkS" user "B.Silkscreen")
		(37 "F.SilkS" user "F.Silkscreen")
		(38 "B.Mask" user)
		(39 "F.Mask" user)
		(40 "Dwgs.User" user "User.Drawings")
		(41 "Cmts.User" user "User.Comments")
		(42 "Eco1.User" user "User.Eco1")
		(43 "Eco2.User" user "User.Eco2")
		(44 "Edge.Cuts" user)
		(45 "Margin" user)
		(46 "B.CrtYd" user "B.Courtyard")
		(47 "F.CrtYd" user "F.Courtyard")
		(48 "B.Fab" user)
		(49 "F.Fab" user)
	)
	(footprint "antmicro-footprints:R_0603_1608Metric"
		(layer "F.Cu")
		(at 59.09 91.2 -90)
		(descr "Resistor SMD 0603")
		(tags "resistor SMD 0603")
		(property "Reference" "R182"
			(at -0.8 -28.389999 90)
			(layer "F.SilkS")
			(effects
				(font
					(size 0.7 0.7)
					(thickness 0.15)
				)
				(justify right bottom)
			)
		)
		(property "Value" "R_0R_22.4A_0603"
			(at 0 1.6 90)
			(layer "F.Fab")
			(effects
				(font
					(size 0.7 0.7)
					(thickness 0.15)
				)
				(justify right bottom)
			)
		)
		(property "Footprint" "antmicro-footprints:R_0603_1608Metric"
			(at 0 0 90)
			(layer "F.Fab")
			(hide yes)
			(effects
				(font
					(size 1.27 1.27)
					(thickness 0.15)
				)
			)
		)
		(property "Datasheet" "https://fscdn.rohm.com/en/products/databook/datasheet/passive/resistor/chip_resistor/pmr-jpw-e.pdf"
			(at 0 0 90)
			(layer "F.Fab")
			(hide yes)
			(effects
				(font
					(size 1.27 1.27)
					(thickness 0.15)
				)
			)
		)
		(property "Author" "Antmicro"
			(at -34.77 148.11 0)
			(layer "F.Fab")
			(hide yes)
			(effects
				(font
					(size 1 1)
					(thickness 0.15)
				)
			)
		)
		(property "License" "Apache-2.0"
			(at -34.77 148.11 0)
			(layer "F.Fab")
			(hide yes)
			(effects
				(font
					(size 1 1)
					(thickness 0.15)
				)
			)
		)
		(property "MPN" "PMR03EZPJ000"
			(at -34.77 148.11 0)
			(layer "F.Fab")
			(hide yes)
			(effects
				(font
					(size 1 1)
					(thickness 0.15)
				)
			)
		)
		(property "Manufacturer" "ROHM Semiconductor"
			(at -34.77 148.11 0)
			(layer "F.Fab")
			(hide yes)
			(effects
				(font
					(size 1 1)
					(thickness 0.15)
				)
			)
		)
		(property "Max. Curr." "22.4A"
			(at -34.77 148.11 0)
			(layer "F.Fab")
			(hide yes)
			(effects
				(font
					(size 1 1)
					(thickness 0.15)
				)
			)
		)
		(property "Tolerance" "template_tolerance"
			(at -34.77 148.11 0)
			(layer "F.Fab")
			(hide yes)
			(effects
				(font
					(size 1 1)
					(thickness 0.15)
				)
			)
		)
		(property "Val" "0R"
			(at -34.77 148.11 0)
			(layer "F.Fab")
			(hide yes)
			(effects
				(font
					(size 1 1)
					(thickness 0.15)
				)
			)
		)
		(sheetname "Supply")
		(sheetfile "supply.kicad_sch")
		(attr smd exclude_from_pos_files exclude_from_bom dnp)
		(fp_line
			(start -0.15 0.4)
			(end 0.15 0.4)
			(stroke
				(width 0.15)
				(type solid)
			)
			(layer "F.SilkS")
		)
		(fp_line
			(start -0.15 -0.4)
			(end 0.15 -0.4)
			(stroke
				(width 0.15)
				(type solid)
			)
			(layer "F.SilkS")
		)
		(fp_rect
			(start -1.25 -0.65)
			(end 1.25 0.65)
			(stroke
				(width 0.05)
				(type solid)
			)
			(fill none)
			(layer "F.CrtYd")
		)
		(fp_rect
			(start -0.8 -0.4)
			(end 0.8 0.4)
			(stroke
				(width 0.15)
				(type solid)
			)
			(fill none)
			(layer "F.Fab")
		)
		(fp_text user "${REFERENCE}"
			(at -1.25 3.898 90)
			(layer "F.Fab")
			(hide yes)
			(effects
				(font
					(size 0.7 0.7)
					(thickness 0.15)
				)
				(justify right bottom)
			)
		)
		(fp_text user "Author: Antmicro"
			(at -1.25 4.9 90)
			(layer "F.Fab")
			(hide yes)
			(effects
				(font
					(size 0.7 0.7)
					(thickness 0.15)
				)
				(justify right bottom)
			)
		)
		(fp_text user "License: Apache-2.0"
			(at -1.25 5.9 90)
			(layer "F.Fab")
			(hide yes)
			(effects
				(font
					(size 0.7 0.7)
					(thickness 0.15)
				)
				(justify right bottom)
			)
		)
		(pad "1" smd roundrect
			(at -0.7 0 270)
			(size 0.8 1)
			(layers "F.Cu" "F.Paste" "F.Mask")
			(roundrect_rratio 0.2)
			(net 787 "+5V_SoM")
			(pintype "passive")
		)
		(pad "2" smd roundrect
			(at 0.7 0 270)
			(size 0.8 1)
			(layers "F.Cu" "F.Paste" "F.Mask")
			(roundrect_rratio 0.2)
			(net 99 "+5V")
			(pintype "passive")
		)
	)
	(footprint "antmicro-footprints:SOD-923"
		(layer "F.Cu")
		(at 68.9 87.925 90)
		(property "Reference" "D33"
			(at -2.775 0.49 90)
			(unlocked yes)
			(layer "F.SilkS")
			(effects
				(font
					(size 0.7 0.7)
					(thickness 0.15)
				)
				(justify left bottom)
			)
		)
		(property "Value" "ESD9X5.0ST5G"
			(at 0 1.3 90)
			(unlocked yes)
			(layer "F.Fab")
			(effects
				(font
					(size 0.7 0.7)
					(thickness 0.15)
				)
				(justify left bottom)
			)
		)
		(property "Footprint" "antmicro-footprints:SOD-923"
			(at 0 0 90)
			(layer "F.Fab")
			(hide yes)
			(effects
				(font
					(size 1.27 1.27)
					(thickness 0.15)
				)
			)
		)
		(property "Datasheet" "https://www.onsemi.com/pdf/datasheet/esd9x3.3st5g-d.pdf"
			(at 0 0 90)
			(layer "F.Fab")
			(hide yes)
			(effects
				(font
					(size 1.27 1.27)
					(thickness 0.15)
				)
			)
		)
		(property "Author" "Antmicro"
			(at 0 0 90)
			(layer "F.Fab")
			(hide yes)
			(effects
				(font
					(size 1 1)
					(thickness 0.15)
				)
			)
		)
		(property "License" "Apache-2.0"
			(at 0 0 90)
			(layer "F.Fab")
			(hide yes)
			(effects
				(font
					(size 1 1)
					(thickness 0.15)
				)
			)
		)
		(property "MPN" "ESD9X5.0ST5G"
			(at 0 0 90)
			(layer "F.Fab")
			(hide yes)
			(effects
				(font
					(size 1 1)
					(thickness 0.15)
				)
			)
		)
		(property "Manufacturer" "ON Semiconductor"
			(at 0 0 90)
			(layer "F.Fab")
			(hide yes)
			(effects
				(font
					(size 1 1)
					(thickness 0.15)
				)
			)
		)
		(sheetname "Supply")
		(sheetfile "supply.kicad_sch")
		(attr smd)
		(fp_line
			(start 0.5 -0.4)
			(end 0.5 -0.3)
			(stroke
				(width 0.15)
				(type solid)
			)
			(layer "F.SilkS")
		)
		(fp_line
			(start -0.16 -0.4)
			(end -0.16 0.4)
			(stroke
				(width 0.15)
				(type solid)
			)
			(layer "F.SilkS")
		)
		(fp_line
			(start -0.5 -0.4)
			(end 0.5 -0.4)
			(stroke
				(width 0.15)
				(type solid)
			)
			(layer "F.SilkS")
		)
		(fp_line
			(start -0.5 -0.3)
			(end -0.5 -0.4)
			(stroke
				(width 0.15)
				(type solid)
			)
			(layer "F.SilkS")
		)
		(fp_line
			(start 0.5 0.4)
			(end 0.5 0.3)
			(stroke
				(width 0.15)
				(type solid)
			)
			(layer "F.SilkS")
		)
		(fp_line
			(start -0.5 0.4)
			(end -0.5 0.3)
			(stroke
				(width 0.15)
				(type solid)
			)
			(layer "F.SilkS")
		)
		(fp_line
			(start -0.5 0.4)
			(end 0.5 0.4)
			(stroke
				(width 0.15)
				(type solid)
			)
			(layer "F.SilkS")
		)
		(fp_rect
			(start -0.68 -0.41)
			(end 0.68 0.41)
			(stroke
				(width 0.05)
				(type solid)
			)
			(fill none)
			(layer "F.CrtYd")
		)
		(fp_line
			(start -0.202 -0.3)
			(end -0.202 0.298)
			(stroke
				(width 0.15)
				(type solid)
			)
			(layer "F.Fab")
		)
		(fp_rect
			(start -0.402 -0.3)
			(end 0.4 0.298)
			(stroke
				(width 0.15)
				(type solid)
			)
			(fill none)
			(layer "F.Fab")
		)
		(fp_text user "Author: Antmicro"
			(at -0.68 5.7 90)
			(layer "F.Fab")
			(hide yes)
			(effects
				(font
					(size 0.7 0.7)
					(thickness 0.15)
				)
				(justify left bottom)
			)
		)
		(fp_text user "License: Apache-2.0"
			(at -0.68 4.5 90)
			(layer "F.Fab")
			(hide yes)
			(effects
				(font
					(size 0.7 0.7)
					(thickness 0.15)
				)
				(justify left bottom)
			)
		)
		(fp_text user "${REFERENCE}"
			(at -0.68 3.3 90)
			(unlocked yes)
			(layer "F.Fab")
			(hide yes)
			(effects
				(font
					(size 0.7 0.7)
					(thickness 0.15)
				)
				(justify left bottom)
			)
		)
		(pad "1" smd roundrect
			(at -0.438 0 90)
			(size 0.4 0.325)
			(layers "F.Cu" "F.Paste" "F.Mask")
			(roundrect_rratio 0.25)
			(net 87 "+3V3")
			(pinfunction "C")
			(pintype "passive")
		)
		(pad "2" smd roundrect
			(at 0.436 0 90)
			(size 0.4 0.325)
			(layers "F.Cu" "F.Paste" "F.Mask")
			(roundrect_rratio 0.25)
			(net 1 "GND")
			(pinfunction "A")
			(pintype "passive")
		)
	)
	(footprint "antmicro-footprints:RJ45_X-2337992-8_Horizontal"
		(layer "F.Cu")
		(at 33.435 108.616397)
		(property "Reference" "J6"
			(at 14.965 1.583603 90)
			(layer "F.SilkS")
			(effects
				(font
					(size 0.7 0.7)
					(thickness 0.15)
				)
				(justify left bottom)
			)
		)
		(property "Value" "Bus_RJ45_5-2337992-8"
			(at -2.6 22 0)
			(layer "F.Fab")
			(effects
				(font
					(size 0.7 0.7)
					(thickness 0.15)
				)
				(justify left bottom)
			)
		)
		(property "Footprint" "antmicro-footprints:RJ45_X-2337992-8_Horizontal"
			(at 0 0 0)
			(layer "F.Fab")
			(hide yes)
			(effects
				(font
					(size 1.27 1.27)
					(thickness 0.15)
				)
			)
		)
		(property "Datasheet" "https://www.te.com/commerce/DocumentDelivery/DDEController?Action=showdoc&DocId=Customer+Drawing%7F5-2337992-8%7FA%7Fpdf%7FEnglish%7FENG_CD_5-2337992-8_A.pdf%7F5-2337992-8"
			(at 0 0 0)
			(layer "F.Fab")
			(hide yes)
			(effects
				(font
					(size 1.27 1.27)
					(thickness 0.15)
				)
			)
		)
		(property "Author" "Antmicro"
			(at 0 0 0)
			(layer "F.Fab")
			(hide yes)
			(effects
				(font
					(size 1 1)
					(thickness 0.15)
				)
			)
		)
		(property "License" "Apache-2.0"
			(at 0 0 0)
			(layer "F.Fab")
			(hide yes)
			(effects
				(font
					(size 1 1)
					(thickness 0.15)
				)
			)
		)
		(property "MPN" "5-2337992-8"
			(at 0 0 0)
			(layer "F.Fab")
			(hide yes)
			(effects
				(font
					(size 1 1)
					(thickness 0.15)
				)
			)
		)
		(property "Manufacturer" "TE Connectivity"
			(at 0 0 0)
			(layer "F.Fab")
			(hide yes)
			(effects
				(font
					(size 1 1)
					(thickness 0.15)
				)
			)
		)
		(property ki_fp_filters "CONN18_5-2337992-8_TEC")
		(sheetname "Ethernet")
		(sheetfile "ethernet.kicad_sch")
		(attr through_hole)
		(fp_line
			(start -2.363 -1.845)
			(end -2.363 4.48)
			(stroke
				(width 0.15)
				(type solid)
			)
			(layer "F.SilkS")
		)
		(fp_line
			(start -2.363 7.217)
			(end -2.363 19.771)
			(stroke
				(width 0.15)
				(type solid)
			)
			(layer "F.SilkS")
		)
		(fp_line
			(start -2.363 19.771)
			(end 13.791 19.771)
			(stroke
				(width 0.15)
				(type solid)
			)
			(layer "F.SilkS")
		)
		(fp_line
			(start 13.791 -1.845)
			(end -2.363 -1.845)
			(stroke
				(width 0.15)
				(type solid)
			)
			(layer "F.SilkS")
		)
		(fp_line
			(start 13.791 4.48)
			(end 13.791 -1.845)
			(stroke
				(width 0.15)
				(type solid)
			)
			(layer "F.SilkS")
		)
		(fp_line
			(start 13.791 19.771)
			(end 13.791 7.217)
			(stroke
				(width 0.15)
				(type solid)
			)
			(layer "F.SilkS")
		)
		(fp_rect
			(start -2.4 -1.8)
			(end 13.9 19.999)
			(stroke
				(width 0.05)
				(type solid)
			)
			(fill none)
			(layer "F.CrtYd")
		)
		(fp_line
			(start -2.237 -1.718)
			(end -2.237 19.644)
			(stroke
				(width 0.15)
				(type solid)
			)
			(layer "F.Fab")
		)
		(fp_line
			(start -2.237 19.644)
			(end 13.665 19.644)
			(stroke
				(width 0.15)
				(type solid)
			)
			(layer "F.Fab")
		)
		(fp_line
			(start 13.665 -1.718)
			(end -2.237 -1.718)
			(stroke
				(width 0.15)
				(type solid)
			)
			(layer "F.Fab")
		)
		(fp_line
			(start 13.665 19.644)
			(end 13.665 -1.718)
			(stroke
				(width 0.15)
				(type solid)
			)
			(layer "F.Fab")
		)
		(fp_text user "Author: Antmicro"
			(at -2.644 24.8 0)
			(layer "F.Fab")
			(hide yes)
			(effects
				(font
					(size 0.7 0.7)
					(thickness 0.15)
				)
				(justify left bottom)
			)
		)
		(fp_text user "${REFERENCE}"
			(at -2.644 23.4 0)
			(layer "F.Fab")
			(hide yes)
			(effects
				(font
					(size 0.7 0.7)
					(thickness 0.15)
				)
				(justify left bottom)
			)
		)
		(fp_text user "License: Apache-2.0"
			(at -2.644 26.2 0)
			(layer "F.Fab")
			(hide yes)
			(effects
				(font
					(size 0.7 0.7)
					(thickness 0.15)
				)
				(justify left bottom)
			)
		)
		(pad "" np_thru_hole circle
			(at 0 8.9)
			(size 3.25 3.25)
			(drill 3.25)
			(layers "*.Cu" "*.Mask")
		)
		(pad "" np_thru_hole circle
			(at 11.429 8.9)
			(size 3.25 3.25)
			(drill 3.25)
			(layers "*.Cu" "*.Mask")
		)
		(pad "1" thru_hole circle
			(at 0 0)
			(size 1.397 1.397)
			(drill 0.889)
			(layers "*.Cu" "*.Mask")
			(remove_unused_layers no)
			(net 67 "GBE_MDI0_P")
			(pinfunction "P1")
			(pintype "bidirectional")
		)
		(pad "2" thru_hole circle
			(at 1.269 2.539)
			(size 1.397 1.397)
			(drill 0.889)
			(layers "*.Cu" "*.Mask")
			(remove_unused_layers no)
			(net 66 "GBE_MDI0_N")
			(pinfunction "P2")
			(pintype "bidirectional")
		)
		(pad "3" thru_hole circle
			(at 2.539 0)
			(size 1.397 1.397)
			(drill 0.889)
			(layers "*.Cu" "*.Mask")
			(remove_unused_layers no)
			(net 69 "GBE_MDI1_P")
			(pinfunction "P3")
			(pintype "bidirectional")
		)
		(pad "4" thru_hole circle
			(at 3.809 2.539)
			(size 1.397 1.397)
			(drill 0.889)
			(layers "*.Cu" "*.Mask")
			(remove_unused_layers no)
			(net 136 "Net-(J6-P4)")
			(pinfunction "P4")
			(pintype "bidirectional")
		)
		(pad "5" thru_hole circle
			(at 5.078 0)
			(size 1.397 1.397)
			(drill 0.889)
			(layers "*.Cu" "*.Mask")
			(remove_unused_layers no)
			(net 136 "Net-(J6-P4)")
			(pinfunction "P5")
			(pintype "bidirectional")
		)
		(pad "6" thru_hole circle
			(at 6.349 2.539)
			(size 1.397 1.397)
			(drill 0.889)
			(layers "*.Cu" "*.Mask")
			(remove_unused_layers no)
			(net 68 "GBE_MDI1_N")
			(pinfunction "P6")
			(pintype "bidirectional")
		)
		(pad "7" thru_hole circle
			(at 7.618 0)
			(size 1.397 1.397)
			(drill 0.889)
			(layers "*.Cu" "*.Mask")
			(remove_unused_layers no)
			(net 74 "GBE_MDI2_P")
			(pinfunction "P7")
			(pintype "bidirectional")
		)
		(pad "8" thru_hole circle
			(at 8.89 2.539)
			(size 1.397 1.397)
			(drill 0.889)
			(layers "*.Cu" "*.Mask")
			(remove_unused_layers no)
			(net 72 "GBE_MDI2_N")
			(pinfunction "P8")
			(pintype "bidirectional")
		)
		(pad "9" thru_hole circle
			(at 10.159 0)
			(size 1.397 1.397)
			(drill 0.889)
			(layers "*.Cu" "*.Mask")
			(remove_unused_layers no)
			(net 77 "GBE_MDI3_P")
			(pinfunction "P9")
			(pintype "bidirectional")
		)
		(pad "10" thru_hole circle
			(at 11.429 2.539)
			(size 1.397 1.397)
			(drill 0.889)
			(layers "*.Cu" "*.Mask")
			(remove_unused_layers no)
			(net 76 "GBE_MDI3_N")
			(pinfunction "P10")
			(pintype "bidirectional")
		)
		(pad "11" thru_hole circle
			(at 0 5.078)
			(size 1.397 1.397)
			(drill 0.889)
			(layers "*.Cu" "*.Mask")
			(remove_unused_layers no)
			(net 121 "/Ethernet/PAIR_12")
			(pinfunction "VC1")
			(pintype "bidirectional")
		)
		(pad "12" thru_hole circle
			(at 2.539 6.339)
			(size 1.397 1.397)
			(drill 0.889)
			(layers "*.Cu" "*.Mask")
			(remove_unused_layers no)
			(net 122 "/Ethernet/PAIR_36")
			(pinfunction "VC2")
			(pintype "bidirectional")
		)
		(pad "13" thru_hole circle
			(at 8.89 6.339)
			(size 1.397 1.397)
			(drill 0.889)
			(layers "*.Cu" "*.Mask")
			(remove_unused_layers no)
			(net 123 "/Ethernet/PAIR_78")
			(pinfunction "VC3")
			(pintype "bidirectional")
		)
		(pad "14" thru_hole circle
			(at 11.429 5.07)
			(size 1.397 1.397)
			(drill 0.889)
			(layers "*.Cu" "*.Mask")
			(remove_unused_layers no)
			(net 124 "/Ethernet/PAIR_910")
			(pinfunction "VC4")
			(pintype "bidirectional")
		)
		(pad "15" thru_hole circle
			(at -0.927 12.958)
			(size 1.524 1.524)
			(drill 1.016)
			(layers "*.Cu" "*.Mask")
			(remove_unused_layers no)
			(net 87 "+3V3")
			(pinfunction "LED_GRN+")
			(pintype "passive")
		)
		(pad "16" thru_hole circle
			(at 1.614 12.958)
			(size 1.524 1.524)
			(drill 1.016)
			(layers "*.Cu" "*.Mask")
			(remove_unused_layers no)
			(net 551 "Net-(J6-LED_GRN-)")
			(pinfunction "LED_GRN-")
			(pintype "passive")
		)
		(pad "17" thru_hole circle
			(at 9.814 12.958)
			(size 1.524 1.524)
			(drill 1.016)
			(layers "*.Cu" "*.Mask")
			(remove_unused_layers no)
			(net 87 "+3V3")
			(pinfunction "LED_YEL+")
			(pintype "passive")
		)
		(pad "18" thru_hole circle
			(at 12.355 12.958)
			(size 1.524 1.524)
			(drill 1.016)
			(layers "*.Cu" "*.Mask")
			(remove_unused_layers no)
			(net 552 "Net-(J6-LED_YEL-)")
			(pinfunction "LED_YEL-")
			(pintype "passive")
		)
		(pad "19" thru_hole circle
			(at -2.136 5.85)
			(size 2.1 2.1)
			(drill 1.6)
			(layers "*.Cu" "*.Mask")
			(remove_unused_layers no)
			(net 715 "Net-(C78-Pad1)")
			(pinfunction "SHIELD")
			(pintype "passive")
		)
		(pad "20" thru_hole circle
			(at 13.563 5.85)
			(size 2.1082 2.1082)
			(drill 1.6002)
			(layers "*.Cu" "*.Mask")
			(remove_unused_layers no)
			(net 715 "Net-(C78-Pad1)")
			(pinfunction "SHIELD")
			(pintype "passive")
		)
	)
)
